# BASEBOARD_FAB2 (Tioga Pass) — schematic netlist excerpt (pin names and nets, part order shuffled) for the footprints in the layout excerpt that follows; sources: Cadence DE-HDL packaged netlist, KiCad conversion of Wiwynn_Tioga_Pass_MB.brd

C4A20  CAP_A  0.1UF 16V 10% X7R  pkg 0402V  page 234 : A = VR_FET_SW_P12V_STBY_PVPP_KLM ; B = GND

(kicad_pcb
	(version 20260206)
	(generator "pcbnew")
	(generator_version "10.0")
	(general
		(thickness 1.6)
		(legacy_teardrops no)
	)
	(paper "A4")
	(title_block
		(title "Wiwynn_Tioga_Pass_MB.brd")
		(comment 1 "Tioga Pass / footprints 188-188 of 4770")
	)
	(layers
		(0 "F.Cu" signal "TOP")
		(4 "In1.Cu" signal "L2GND")
		(6 "In2.Cu" signal "L3")
		(8 "In3.Cu" signal "L4GND")
		(10 "In4.Cu" signal "L5")
		(12 "In5.Cu" signal "L6GND")
		(14 "In6.Cu" signal "L7VCC")
		(16 "In7.Cu" signal "L8VCC")
		(18 "In8.Cu" signal "L9GND")
		(20 "In9.Cu" signal "L10")
		(22 "In10.Cu" signal "L11GND")
		(24 "In11.Cu" signal "L12")
		(26 "In12.Cu" signal "L13GND")
		(2 "B.Cu" signal "BOTTOM")
		(9 "F.Adhes" user "F.Adhesive")
		(11 "B.Adhes" user "B.Adhesive")
		(13 "F.Paste" user "Package Geometry/Pastemask Top")
		(15 "B.Paste" user "Package Geometry/Pastemask Bottom")
		(5 "F.SilkS" user "Ref Des/Silkscreen Top")
		(7 "B.SilkS" user "Ref Des/Silkscreen Bottom")
		(1 "F.Mask" user "Board Geometry/Soldermask Top")
		(3 "B.Mask" user "Board Geometry/Soldermask Bottom")
		(17 "Dwgs.User" user "User.Drawings")
		(19 "Cmts.User" user "User.Comments")
		(21 "Eco1.User" user "User.Eco1")
		(23 "Eco2.User" user "User.Eco2")
		(25 "Edge.Cuts" user "Board Geometry/Outline")
		(27 "Margin" user)
		(31 "F.CrtYd" user "Package Geometry/Place Bound Top")
		(29 "B.CrtYd" user "Package Geometry/Place Bound Bottom")
		(35 "F.Fab" user "Ref Des/Assembly Top")
		(33 "B.Fab" user "Ref Des/Assembly Bottom")
	)
	(footprint ""
		(layer "F.Cu")
		(at 181.9656 -135.9662 180)
		(property "Reference" "C4A20"
			(at 0 0 180)
			(layer "F.SilkS")
			(hide yes)
			(effects
				(font
					(size 1.27 1.27)
				)
			)
		)
		(property "Value" ""
			(at 0 0 180)
			(layer "F.Fab")
			(effects
				(font
					(size 1.27 1.27)
				)
			)
		)
		(duplicate_pad_numbers_are_jumpers no)
		(fp_poly
			(pts
				(xy 0.3048 -0.1016) (xy 0.3048 0.9906) (xy -0.3048 0.9906) (xy -0.3048 -0.1016)
			)
			(stroke
				(width 0)
				(type default)
			)
			(fill no)
			(layer "F.CrtYd")
		)
		(fp_line
			(start 0.3048 0.9906)
			(end 0.3048 -0.1016)
			(stroke
				(width 0.1)
				(type default)
			)
			(layer "F.Fab")
		)
		(fp_line
			(start 0.3048 -0.1016)
			(end -0.3048 -0.1016)
			(stroke
				(width 0.1)
				(type default)
			)
			(layer "F.Fab")
		)
		(fp_line
			(start -0.3048 0.9906)
			(end 0.3048 0.9906)
			(stroke
				(width 0.1)
				(type default)
			)
			(layer "F.Fab")
		)
		(fp_line
			(start -0.3048 -0.1016)
			(end -0.3048 0.9906)
			(stroke
				(width 0.1)
				(type default)
			)
			(layer "F.Fab")
		)
		(pad "1" smd rect
			(at 0 0 180)
			(size 0.508 0.508)
			(layers "F.Cu" "F.Mask" "F.Paste")
			(net "VR_FET_SW_P12V_STBY_PVPP_KLM")
		)
		(pad "2" smd rect
			(at 0 0.889 180)
			(size 0.508 0.508)
			(layers "F.Cu" "F.Mask" "F.Paste")
			(net "GND")
		)
		(zone
			(layer "F.Cu")
			(hatch none 0.5)
			(connect_pads
				(clearance 0)
			)
			(min_thickness 0.25)
			(keepout
				(tracks not_allowed)
				(vias allowed)
				(pads allowed)
				(copperpour not_allowed)
				(footprints allowed)
			)
			(placement
				(enabled no)
				(sheetname "")
			)
			(fill
				(thermal_gap 0.5)
				(thermal_bridge_width 0.5)
				(island_removal_mode 0)
			)
			(polygon
				(pts
					(xy 182.2196 -136.6012) (xy 181.7116 -136.6012) (xy 181.7116 -136.2202) (xy 182.2196 -136.2202)
				)
			)
		)
		(zone
			(layer "F.Cu")
			(hatch none 0.5)
			(connect_pads
				(clearance 0)
			)
			(min_thickness 0.25)
			(keepout
				(tracks allowed)
				(vias not_allowed)
				(pads allowed)
				(copperpour not_allowed)
				(footprints allowed)
			)
			(placement
				(enabled no)
				(sheetname "")
			)
			(fill
				(thermal_gap 0.5)
				(thermal_bridge_width 0.5)
				(island_removal_mode 0)
			)
			(polygon
				(pts
					(xy 182.2196 -136.2202) (xy 181.7116 -136.2202) (xy 181.7116 -136.6012) (xy 182.2196 -136.6012)
				)
			)
		)
	)
)
